(kicad_pcb
	(version 20260206)
	(generator "pcbnew")
	(generator_version "10.0")
	(general
		(thickness 1.6)
		(legacy_teardrops no)
	)
	(paper "A4")
	(title_block
		(title "Bryce Canyon_F.DPB_16315-1-OCP.brd")
		(comment 1 "Bryce Canyon / footprints 647-653 of 2223")
	)
	(layers
		(0 "F.Cu" signal "TOP")
		(4 "In1.Cu" signal "L2GND")
		(6 "In2.Cu" signal "L3")
		(8 "In3.Cu" signal "L4GND")
		(10 "In4.Cu" signal "L5")
		(12 "In5.Cu" signal "L6VCC")
		(14 "In6.Cu" signal "L7VCC")
		(16 "In7.Cu" signal "L8")
		(18 "In8.Cu" signal "L9GND")
		(20 "In9.Cu" signal "L10")
		(22 "In10.Cu" signal "L11GND")
		(2 "B.Cu" signal "BOTTOM")
		(9 "F.Adhes" user "F.Adhesive")
		(11 "B.Adhes" user "B.Adhesive")
		(13 "F.Paste" user "Package Geometry/Pastemask Top")
		(15 "B.Paste" user "Package Geometry/Pastemask Bottom")
		(5 "F.SilkS" user "Ref Des/Silkscreen Top")
		(7 "B.SilkS" user "Ref Des/Silkscreen Bottom")
		(1 "F.Mask" user "Board Geometry/Soldermask Top")
		(3 "B.Mask" user "Board Geometry/Soldermask Bottom")
		(17 "Dwgs.User" user "User.Drawings")
		(19 "Cmts.User" user "User.Comments")
		(21 "Eco1.User" user "User.Eco1")
		(23 "Eco2.User" user "User.Eco2")
		(25 "Edge.Cuts" user "Board Geometry/Outline")
		(27 "Margin" user)
		(31 "F.CrtYd" user "Package Geometry/Place Bound Top")
		(29 "B.CrtYd" user "Package Geometry/Place Bound Bottom")
		(35 "F.Fab" user "Ref Des/Assembly Top")
		(33 "B.Fab" user "Ref Des/Assembly Bottom")
	)
	(footprint ""
		(layer "F.Cu")
		(at 77.942948 -54.523894 90)
		(property "Reference" "C387"
			(at 0 0 90)
			(layer "F.SilkS")
			(hide yes)
			(effects
				(font
					(size 1.27 1.27)
				)
			)
		)
		(property "Value" "SCD033U25V2KX-GP"
			(at 1.1811 -2.7051 90)
			(unlocked yes)
			(layer "F.Fab")
			(hide yes)
			(effects
				(font
					(size 1.016 1.016)
					(thickness 0.1524)
				)
			)
		)
		(property "Device Type" "C402H22"
			(at 1.1811 -4.2291 90)
			(unlocked yes)
			(layer "F.Fab")
			(hide yes)
			(effects
				(font
					(size 1.016 1.016)
					(thickness 0.1524)
				)
			)
		)
		(duplicate_pad_numbers_are_jumpers no)
		(fp_rect
			(start -0.4318 0.9525)
			(end 0.4318 -0.9525)
			(stroke
				(width 0)
				(type default)
			)
			(fill no)
			(layer "F.CrtYd")
		)
		(fp_rect
			(start -0.4318 0.9525)
			(end 0.4318 -0.9525)
			(stroke
				(width 0)
				(type default)
			)
			(fill no)
			(layer "F.Fab")
		)
		(pad "1" smd custom
			(at 0 -0.4445 90)
			(size 0.1524 0.1524)
			(layers "F.Cu" "F.Mask" "F.Paste")
			(net "P12V_A")
			(options
				(clearance outline)
				(anchor circle)
			)
			(primitives
				(gr_poly
					(pts
						(arc
							(start 0.3048 -0.2032)
							(mid 0.275042 -0.275042)
							(end 0.2032 -0.3048)
						)
						(arc
							(start -0.2032 -0.3048)
							(mid -0.275042 -0.275042)
							(end -0.3048 -0.2032)
						)
						(arc
							(start -0.3048 0.2032)
							(mid -0.275042 0.275042)
							(end -0.2032 0.3048)
						)
						(arc
							(start 0.2032 0.3048)
							(mid 0.275042 0.275042)
							(end 0.3048 0.2032)
						)
					)
					(width 0)
					(fill yes)
				)
			)
		)
		(pad "2" smd custom
			(at 0 0.4445 90)
			(size 0.1524 0.1524)
			(layers "F.Cu" "F.Mask" "F.Paste")
			(net "SW_HDD_N26")
			(options
				(clearance outline)
				(anchor circle)
			)
			(primitives
				(gr_poly
					(pts
						(arc
							(start 0.3048 -0.2032)
							(mid 0.275042 -0.275042)
							(end 0.2032 -0.3048)
						)
						(arc
							(start -0.2032 -0.3048)
							(mid -0.275042 -0.275042)
							(end -0.3048 -0.2032)
						)
						(arc
							(start -0.3048 0.2032)
							(mid -0.275042 0.275042)
							(end -0.2032 0.3048)
						)
						(arc
							(start 0.2032 0.3048)
							(mid 0.275042 0.275042)
							(end 0.3048 0.2032)
						)
					)
					(width 0)
					(fill yes)
				)
			)
		)
	)
	(footprint ""
		(layer "F.Cu")
		(at 35.797998 -62.169294 -90)
		(property "Reference" "R682"
			(at 0 0 270)
			(layer "F.SilkS")
			(hide yes)
			(effects
				(font
					(size 1.27 1.27)
				)
			)
		)
		(property "Value" "10KR2F-2-GP"
			(at 0.064008 -3.993896 270)
			(unlocked yes)
			(layer "F.Fab")
			(hide yes)
			(effects
				(font
					(size 1.016 1.016)
					(thickness 0.1524)
				)
			)
		)
		(property "Device Type" "R402H16"
			(at 0.064008 -5.517896 270)
			(unlocked yes)
			(layer "F.Fab")
			(hide yes)
			(effects
				(font
					(size 1.016 1.016)
					(thickness 0.1524)
				)
			)
		)
		(duplicate_pad_numbers_are_jumpers no)
		(fp_line
			(start -0.508 -0.9398)
			(end -0.508 0.9398)
			(stroke
				(width 0.1524)
				(type default)
			)
			(layer "F.SilkS")
		)
		(fp_line
			(start 0.508 -0.9398)
			(end -0.508 -0.9398)
			(stroke
				(width 0.1524)
				(type default)
			)
			(layer "F.SilkS")
		)
		(fp_rect
			(start -0.508 0.9398)
			(end 0.508 -0.9398)
			(stroke
				(width 0)
				(type default)
			)
			(fill no)
			(layer "F.CrtYd")
		)
		(fp_rect
			(start -0.508 0.9398)
			(end 0.508 -0.9398)
			(stroke
				(width 0)
				(type default)
			)
			(fill no)
			(layer "F.Fab")
		)
		(pad "1" smd custom
			(at 0 -0.4445 270)
			(size 0.1397 0.1397)
			(layers "F.Cu" "F.Mask" "F.Paste")
			(net "P3V3_STBY_A")
			(options
				(clearance outline)
				(anchor circle)
			)
			(primitives
				(gr_poly
					(pts
						(arc
							(start -0.1778 -0.2794)
							(mid -0.249642 -0.249642)
							(end -0.2794 -0.1778)
						)
						(arc
							(start -0.2794 0.1778)
							(mid -0.249642 0.249642)
							(end -0.1778 0.2794)
						)
						(arc
							(start 0.1778 0.2794)
							(mid 0.249642 0.249642)
							(end 0.2794 0.1778)
						)
						(arc
							(start 0.2794 -0.1778)
							(mid 0.249642 -0.249642)
							(end 0.1778 -0.2794)
						)
					)
					(width 0)
					(fill yes)
				)
			)
		)
		(pad "2" smd custom
			(at 0 0.4445 270)
			(size 0.1397 0.1397)
			(layers "F.Cu" "F.Mask" "F.Paste")
			(net "HDD_PRSNT_24")
			(options
				(clearance outline)
				(anchor circle)
			)
			(primitives
				(gr_poly
					(pts
						(arc
							(start -0.1778 -0.2794)
							(mid -0.249642 -0.249642)
							(end -0.2794 -0.1778)
						)
						(arc
							(start -0.2794 0.1778)
							(mid -0.249642 0.249642)
							(end -0.1778 0.2794)
						)
						(arc
							(start 0.1778 0.2794)
							(mid 0.249642 0.249642)
							(end 0.2794 0.1778)
						)
						(arc
							(start 0.2794 -0.1778)
							(mid 0.249642 -0.249642)
							(end 0.1778 -0.2794)
						)
					)
					(width 0)
					(fill yes)
				)
			)
		)
	)
	(footprint ""
		(layer "F.Cu")
		(at 146.630898 -177.778918 -90)
		(property "Reference" "C248"
			(at 0 0 270)
			(layer "F.SilkS")
			(hide yes)
			(effects
				(font
					(size 1.27 1.27)
				)
			)
		)
		(property "Value" "SC1U16V3KX-5GP"
			(at 0 -2.8194 270)
			(unlocked yes)
			(layer "F.Fab")
			(hide yes)
			(effects
				(font
					(size 1.016 1.016)
					(thickness 0.1524)
				)
			)
		)
		(property "Device Type" "C603H36"
			(at 0 -4.3434 270)
			(unlocked yes)
			(layer "F.Fab")
			(hide yes)
			(effects
				(font
					(size 1.016 1.016)
					(thickness 0.1524)
				)
			)
		)
		(duplicate_pad_numbers_are_jumpers no)
		(fp_line
			(start 0.508 0)
			(end -0.508 0)
			(stroke
				(width 0.2032)
				(type default)
			)
			(layer "F.SilkS")
		)
		(fp_rect
			(start -0.5842 1.3335)
			(end 0.5842 -1.3335)
			(stroke
				(width 0)
				(type default)
			)
			(fill no)
			(layer "F.CrtYd")
		)
		(fp_rect
			(start -0.5842 1.3335)
			(end 0.5842 -1.3335)
			(stroke
				(width 0)
				(type default)
			)
			(fill no)
			(layer "F.Fab")
		)
		(pad "1" smd custom
			(at 0 -0.762 270)
			(size 0.2159 0.2159)
			(layers "F.Cu" "F.Mask" "F.Paste")
			(net "P5V_HDD16")
			(options
				(clearance outline)
				(anchor circle)
			)
			(primitives
				(gr_poly
					(pts
						(arc
							(start -0.3302 -0.4318)
							(mid -0.402042 -0.402042)
							(end -0.4318 -0.3302)
						)
						(arc
							(start -0.4318 0.3302)
							(mid -0.402042 0.402042)
							(end -0.3302 0.4318)
						)
						(arc
							(start 0.3302 0.4318)
							(mid 0.402042 0.402042)
							(end 0.4318 0.3302)
						)
						(arc
							(start 0.4318 -0.3302)
							(mid 0.402042 -0.402042)
							(end 0.3302 -0.4318)
						)
					)
					(width 0)
					(fill yes)
				)
			)
		)
		(pad "2" smd custom
			(at 0 0.762 270)
			(size 0.2159 0.2159)
			(layers "F.Cu" "F.Mask" "F.Paste")
			(net "GND")
			(options
				(clearance outline)
				(anchor circle)
			)
			(primitives
				(gr_poly
					(pts
						(arc
							(start -0.3302 -0.4318)
							(mid -0.402042 -0.402042)
							(end -0.4318 -0.3302)
						)
						(arc
							(start -0.4318 0.3302)
							(mid -0.402042 0.402042)
							(end -0.3302 0.4318)
						)
						(arc
							(start 0.3302 0.4318)
							(mid 0.402042 0.402042)
							(end 0.4318 0.3302)
						)
						(arc
							(start 0.4318 -0.3302)
							(mid 0.402042 -0.402042)
							(end 0.3302 -0.4318)
						)
					)
					(width 0)
					(fill yes)
				)
			)
		)
	)
	(footprint ""
		(layer "F.Cu")
		(at 101.1555 -185.042302)
		(property "Reference" "Q266"
			(at 0 0 0)
			(layer "F.SilkS")
			(hide yes)
			(effects
				(font
					(size 1.27 1.27)
				)
			)
		)
		(property "Value" "SSM3K324R-GP"
			(at 0.127 -8.9662 0)
			(unlocked yes)
			(layer "F.Fab")
			(hide yes)
			(effects
				(font
					(size 1.016 1.016)
					(thickness 0.1524)
				)
			)
		)
		(property "Device Type" "SOT23DGS2D4H35"
			(at 0.127 -10.4902 0)
			(unlocked yes)
			(layer "F.Fab")
			(hide yes)
			(effects
				(font
					(size 1.016 1.016)
					(thickness 0.1524)
				)
			)
		)
		(duplicate_pad_numbers_are_jumpers no)
		(fp_line
			(start -1.651 -1.778)
			(end -1.651 1.778)
			(stroke
				(width 0.1524)
				(type default)
			)
			(layer "F.SilkS")
		)
		(fp_line
			(start -1.651 1.778)
			(end 1.651 1.778)
			(stroke
				(width 0.1524)
				(type default)
			)
			(layer "F.SilkS")
		)
		(fp_line
			(start 1.651 -1.778)
			(end -1.651 -1.778)
			(stroke
				(width 0.1524)
				(type default)
			)
			(layer "F.SilkS")
		)
		(fp_line
			(start 1.651 1.778)
			(end 1.651 -1.778)
			(stroke
				(width 0.1524)
				(type default)
			)
			(layer "F.SilkS")
		)
		(fp_poly
			(pts
				(xy -1.778 1.8796) (xy -1.778 -1.8796) (xy 1.778 -1.8796) (xy 1.778 1.8796)
			)
			(stroke
				(width 0)
				(type default)
			)
			(fill no)
			(layer "F.CrtYd")
		)
		(fp_poly
			(pts
				(xy -1.778 1.8796) (xy -1.778 -1.8796) (xy 1.778 -1.8796) (xy 1.778 1.8796)
			)
			(stroke
				(width 0)
				(type default)
			)
			(fill no)
			(layer "F.Fab")
		)
		(pad "D" smd custom
			(at 0 -0.9525)
			(size 0.1905 0.1905)
			(layers "F.Cu" "F.Mask" "F.Paste")
			(net "DRV_ACT_3_N")
			(options
				(clearance outline)
				(anchor circle)
			)
			(primitives
				(gr_poly
					(pts
						(arc
							(start -0.1778 0.5715)
							(mid -0.321484 0.511984)
							(end -0.381 0.3683)
						)
						(arc
							(start -0.381 -0.3683)
							(mid -0.321484 -0.511984)
							(end -0.1778 -0.5715)
						)
						(arc
							(start 0.1778 -0.5715)
							(mid 0.321484 -0.511984)
							(end 0.381 -0.3683)
						)
						(arc
							(start 0.381 0.3683)
							(mid 0.321484 0.511984)
							(end 0.1778 0.5715)
						)
					)
					(width 0)
					(fill yes)
				)
			)
		)
		(pad "G" smd custom
			(at -0.98425 0.9525)
			(size 0.1905 0.1905)
			(layers "F.Cu" "F.Mask" "F.Paste")
			(net "DRIVE_A_3_ACT")
			(options
				(clearance outline)
				(anchor circle)
			)
			(primitives
				(gr_poly
					(pts
						(arc
							(start -0.1778 0.5715)
							(mid -0.321484 0.511984)
							(end -0.381 0.3683)
						)
						(arc
							(start -0.381 -0.3683)
							(mid -0.321484 -0.511984)
							(end -0.1778 -0.5715)
						)
						(arc
							(start 0.1778 -0.5715)
							(mid 0.321484 -0.511984)
							(end 0.381 -0.3683)
						)
						(arc
							(start 0.381 0.3683)
							(mid 0.321484 0.511984)
							(end 0.1778 0.5715)
						)
					)
					(width 0)
					(fill yes)
				)
			)
		)
		(pad "S" smd custom
			(at 0.98425 0.9525)
			(size 0.1905 0.1905)
			(layers "F.Cu" "F.Mask" "F.Paste")
			(net "GND")
			(options
				(clearance outline)
				(anchor circle)
			)
			(primitives
				(gr_poly
					(pts
						(arc
							(start -0.1778 0.5715)
							(mid -0.321484 0.511984)
							(end -0.381 0.3683)
						)
						(arc
							(start -0.381 -0.3683)
							(mid -0.321484 -0.511984)
							(end -0.1778 -0.5715)
						)
						(arc
							(start 0.1778 -0.5715)
							(mid 0.321484 -0.511984)
							(end 0.381 -0.3683)
						)
						(arc
							(start 0.381 0.3683)
							(mid 0.321484 0.511984)
							(end 0.1778 0.5715)
						)
					)
					(width 0)
					(fill yes)
				)
			)
		)
	)
	(footprint ""
		(layer "F.Cu")
		(at 381.61595 -183.620918)
		(property "Reference" "TP102"
			(at 0 0 0)
			(layer "F.SilkS")
			(hide yes)
			(effects
				(font
					(size 1.27 1.27)
				)
			)
		)
		(property "Value" "TPAD32-GP"
			(at -0.0508 -1.6764 0)
			(unlocked yes)
			(layer "F.Fab")
			(hide yes)
			(effects
				(font
					(size 1.016 1.016)
					(thickness 0.1524)
				)
			)
		)
		(property "Device Type" "TPAD32"
			(at -0.0508 -3.2004 0)
			(unlocked yes)
			(layer "F.Fab")
			(hide yes)
			(effects
				(font
					(size 1.016 1.016)
					(thickness 0.1524)
				)
			)
		)
		(duplicate_pad_numbers_are_jumpers no)
		(fp_poly
			(pts
				(arc
					(start 0.4064 0)
					(mid -0.4064 0)
					(end 0.4064 0)
				)
			)
			(stroke
				(width 0)
				(type default)
			)
			(fill no)
			(layer "F.CrtYd")
		)
		(fp_poly
			(pts
				(arc
					(start 0.7112 0)
					(mid -0.7112 0)
					(end 0.7112 0)
				)
			)
			(stroke
				(width 0)
				(type default)
			)
			(fill no)
			(layer "F.Fab")
		)
		(pad "1" smd circle
			(at 0 0)
			(size 0.8128 0.8128)
			(layers "F.Cu" "F.Mask" "F.Paste")
			(net "ACT_HDD_20")
		)
	)
	(footprint ""
		(layer "F.Cu")
		(at 154.29484 -140.531596)
		(property "Reference" "C553"
			(at 0 0 0)
			(layer "F.SilkS")
			(hide yes)
			(effects
				(font
					(size 1.27 1.27)
				)
			)
		)
		(property "Value" "SC1U16V3KX-5GP"
			(at 0 -2.8194 0)
			(unlocked yes)
			(layer "F.Fab")
			(hide yes)
			(effects
				(font
					(size 1.016 1.016)
					(thickness 0.1524)
				)
			)
		)
		(property "Device Type" "C603H36"
			(at 0 -4.3434 0)
			(unlocked yes)
			(layer "F.Fab")
			(hide yes)
			(effects
				(font
					(size 1.016 1.016)
					(thickness 0.1524)
				)
			)
		)
		(duplicate_pad_numbers_are_jumpers no)
		(fp_line
			(start 0.508 0)
			(end -0.508 0)
			(stroke
				(width 0.2032)
				(type default)
			)
			(layer "F.SilkS")
		)
		(fp_rect
			(start -0.5842 1.3335)
			(end 0.5842 -1.3335)
			(stroke
				(width 0)
				(type default)
			)
			(fill no)
			(layer "F.CrtYd")
		)
		(fp_rect
			(start -0.5842 1.3335)
			(end 0.5842 -1.3335)
			(stroke
				(width 0)
				(type default)
			)
			(fill no)
			(layer "F.Fab")
		)
		(pad "1" smd custom
			(at 0 -0.762)
			(size 0.2159 0.2159)
			(layers "F.Cu" "F.Mask" "F.Paste")
			(net "MB0_CM_UV_R")
			(options
				(clearance outline)
				(anchor circle)
			)
			(primitives
				(gr_poly
					(pts
						(arc
							(start -0.3302 -0.4318)
							(mid -0.402042 -0.402042)
							(end -0.4318 -0.3302)
						)
						(arc
							(start -0.4318 0.3302)
							(mid -0.402042 0.402042)
							(end -0.3302 0.4318)
						)
						(arc
							(start 0.3302 0.4318)
							(mid 0.402042 0.402042)
							(end 0.4318 0.3302)
						)
						(arc
							(start 0.4318 -0.3302)
							(mid 0.402042 -0.402042)
							(end 0.3302 -0.4318)
						)
					)
					(width 0)
					(fill yes)
				)
			)
		)
		(pad "2" smd custom
			(at 0 0.762)
			(size 0.2159 0.2159)
			(layers "F.Cu" "F.Mask" "F.Paste")
			(net "AGND_CURRENT_MONOA")
			(options
				(clearance outline)
				(anchor circle)
			)
			(primitives
				(gr_poly
					(pts
						(arc
							(start -0.3302 -0.4318)
							(mid -0.402042 -0.402042)
							(end -0.4318 -0.3302)
						)
						(arc
							(start -0.4318 0.3302)
							(mid -0.402042 0.402042)
							(end -0.3302 0.4318)
						)
						(arc
							(start 0.3302 0.4318)
							(mid 0.402042 0.402042)
							(end 0.4318 0.3302)
						)
						(arc
							(start 0.4318 -0.3302)
							(mid 0.402042 -0.402042)
							(end 0.3302 -0.4318)
						)
					)
					(width 0)
					(fill yes)
				)
			)
		)
	)
	(footprint ""
		(layer "F.Cu")
		(at 266.24661 -141.491462 -90)
		(property "Reference" "R993"
			(at 0 0 270)
			(layer "F.SilkS")
			(hide yes)
			(effects
				(font
					(size 1.27 1.27)
				)
			)
		)
		(property "Value" "100KR2F-L1-GP"
			(at 0.064008 -3.993896 270)
			(unlocked yes)
			(layer "F.Fab")
			(hide yes)
			(effects
				(font
					(size 1.016 1.016)
					(thickness 0.1524)
				)
			)
		)
		(property "Device Type" "R402H16"
			(at 0.064008 -5.517896 270)
			(unlocked yes)
			(layer "F.Fab")
			(hide yes)
			(effects
				(font
					(size 1.016 1.016)
					(thickness 0.1524)
				)
			)
		)
		(duplicate_pad_numbers_are_jumpers no)
		(fp_line
			(start -0.508 -0.9398)
			(end -0.508 0.9398)
			(stroke
				(width 0.1524)
				(type default)
			)
			(layer "F.SilkS")
		)
		(fp_line
			(start 0.508 -0.9398)
			(end -0.508 -0.9398)
			(stroke
				(width 0.1524)
				(type default)
			)
			(layer "F.SilkS")
		)
		(fp_rect
			(start -0.508 0.9398)
			(end 0.508 -0.9398)
			(stroke
				(width 0)
				(type default)
			)
			(fill no)
			(layer "F.CrtYd")
		)
		(fp_rect
			(start -0.508 0.9398)
			(end 0.508 -0.9398)
			(stroke
				(width 0)
				(type default)
			)
			(fill no)
			(layer "F.Fab")
		)
		(pad "1" smd custom
			(at 0 -0.4445 270)
			(size 0.1397 0.1397)
			(layers "F.Cu" "F.Mask" "F.Paste")
			(net "PCIE_COMP_B_PCIE_RST_1")
			(options
				(clearance outline)
				(anchor circle)
			)
			(primitives
				(gr_poly
					(pts
						(arc
							(start -0.1778 -0.2794)
							(mid -0.249642 -0.249642)
							(end -0.2794 -0.1778)
						)
						(arc
							(start -0.2794 0.1778)
							(mid -0.249642 0.249642)
							(end -0.1778 0.2794)
						)
						(arc
							(start 0.1778 0.2794)
							(mid 0.249642 0.249642)
							(end 0.2794 0.1778)
						)
						(arc
							(start 0.2794 -0.1778)
							(mid 0.249642 -0.249642)
							(end 0.1778 -0.2794)
						)
					)
					(width 0)
					(fill yes)
				)
			)
		)
		(pad "2" smd custom
			(at 0 0.4445 270)
			(size 0.1397 0.1397)
			(layers "F.Cu" "F.Mask" "F.Paste")
			(net "GND")
			(options
				(clearance outline)
				(anchor circle)
			)
			(primitives
				(gr_poly
					(pts
						(arc
							(start -0.1778 -0.2794)
							(mid -0.249642 -0.249642)
							(end -0.2794 -0.1778)
						)
						(arc
							(start -0.2794 0.1778)
							(mid -0.249642 0.249642)
							(end -0.1778 0.2794)
						)
						(arc
							(start 0.1778 0.2794)
							(mid 0.249642 0.249642)
							(end 0.2794 0.1778)
						)
						(arc
							(start 0.2794 -0.1778)
							(mid 0.249642 -0.249642)
							(end 0.1778 -0.2794)
						)
					)
					(width 0)
					(fill yes)
				)
			)
		)
	)
)
